Altium Designer Pick and Place Locations
C:\Users\<user>\Desktop\WorkNotes\Projects\PTP\Time-Appliance-Project-master\Time-Card\GNSS\UBlox\M2-NEO-M9N\ECAD\Project Outputs for M2_NEO-M9N_MODULE\Pick Place for M2_NEO-M9N_MODULE(845-XXXXX_PCBA_projectname).txt

========================================================================================================================
File Design Information:

Date:       01/07/23
Time:       12:36
Revision:   Not in VersionControl
Variant:    845-XXXXX_PCBA_projectname
Units used: mil

Designator Comment                   Layer    Footprint                    Center-X(mil) Center-Y(mil) Rotation Description                                                                                       
Q2         2N7002W                   TopLayer FP-419AB-01-IPC_C            248.031       551.181       90       "MOSFET N-CH 60V 115MA SOT-323"                                                                   
LED1       Green                     TopLayer led0603                      336.156       574.960       90       "LED High-Power Uni-Color Green 574nm 2-Pin Chip LED T/R"                                         
R16        1K_1%_0402                TopLayer RESC1005X40X25NL05T05        336.704       485.654       270      "Chip Resistor, 1 KOhm, +/- 1%, 100 mW, -55 to 155 degC, 0402 (1005 Metric), RoHS, Tape and Reel" 
R15        0_5%_0402                 TopLayer RESC1005X40X25NL05T10        165.354       523.622       90       ""                                                                                                
R14        DNI_0_5%_0402             TopLayer RESC1005X40X25NL05T10        122.047       523.622       90       ""                                                                                                
R13        0_5%_0402                 TopLayer RESC1005X40X25NL05T10        314.961       271.654       270      ""                                                                                                
R12        0_5%_0402                 TopLayer RESC1005X40X25NL05T10        149.606       271.654       270      ""                                                                                                
R11        10K_5%_0402               TopLayer RESC1005X40X25LL05T10        401.575       523.622       270      ""                                                                                                
R2         10K_5%_0402               TopLayer RESC1005X40X25LL05T10        460.630       523.622       270      ""                                                                                                
C7         47uF_6.3V_1206            TopLayer FP-GRM31C-0_2-e0_3_0_8-IPC_C 681.102       377.953       0        "Chip Multilayer Ceramic Capacitors for General Purpose, 1206, 47uF, X5R, 15%, 20%, 6.3V"         
C6         47uF_6.3V_1206            TopLayer FP-GRM31C-0_2-e0_3_0_8-IPC_C 681.102       468.504       0        "Chip Multilayer Ceramic Capacitors for General Purpose, 1206, 47uF, X5R, 15%, 20%, 6.3V"         
R7         "0 ohm 0402"              TopLayer r0402                        649.606       1417.323      180      "RES SMD 0 OHM JUMPER 1/16W 0402"                                                                 
Q1         DMG2302UKQ-7              TopLayer SOT23                        439.575       1401.575      90       "N-Channel 20 V 2.8A (Ta) 660mW (Ta) Surface Mount SOT-23-3"                                      
C5         "10nF 50V 0402"           TopLayer c0402                        255.905       1417.323      180      "CAP CER 10000PF 50V X7R 0402"                                                                    
U1         NEO-M9N-00B               TopLayer IC_NEO-M9N                   429.134       940.945       90       "GNSS module, Flash, TCXO, SAW, LNA, LCC, 12x16 mm Professional Grade"                            
TP11       1MM                       TopLayer TP1MM                        519.685       606.299       90       "Test Point 1MM diameter"                                                                         
TP10       1MM                       TopLayer TP1MM                        570.866       606.299       90       "Test Point 1MM diameter"                                                                         
TP9        1MM                       TopLayer TP1MM                        464.567       606.299       0        "Test Point 1MM diameter"                                                                         
TP8        1MM                       TopLayer TP1MM                        409.449       606.299       0        "Test Point 1MM diameter"                                                                         
TP7        1MM                       TopLayer TP1MM                        791.339       1185.039      0        "Test Point 1MM diameter"                                                                         
TP6        1MM                       TopLayer TP1MM                        669.291       1476.378      0        "Test Point 1MM diameter"                                                                         
TP5        1MM                       TopLayer TP1MM                        590.551       1287.402      0        "Test Point 1MM diameter"                                                                         
TP4        1MM                       TopLayer TP1MM                        464.567       1279.528      0        "Test Point 1MM diameter"                                                                         
TP1        1MM                       TopLayer TP1MM                        696.850       1271.653      0        "Test Point 1MM diameter"                                                                         
R8         "0 ohm 0402"              TopLayer r0402                        204.724       271.653       270      "RES SMD 0 OHM JUMPER 1/16W 0402"                                                                 
R5         "0 ohm 0402"              TopLayer r0402                        259.842       271.653       270      "RES SMD 0 OHM JUMPER 1/16W 0402"                                                                 
R4         "10 OHM 1/4W 0603"        TopLayer r0603                        263.779       1354.331      180      "Res Surge Chip Thick Film 0603 10 Ohm 1% 1/4W ±200ppm/°C Molded Paper T/R"                       
R3         1K_1%_0402                TopLayer RESC1005X40X25NL05T05        472.441       417.323       0        "Chip Resistor, 1 KOhm, +/- 1%, 100 mW, -55 to 155 degC, 0402 (1005 Metric), RoHS, Tape and Reel" 
R1         "0 ohm 0402"              TopLayer r0402                        393.701       1275.591      180      "RES SMD 0 OHM JUMPER 1/16W 0402"                                                                 
LED2       Green                     TopLayer led0603                      472.441       346.457       0        "LED High-Power Uni-Color Green 574nm 2-Pin Chip LED T/R"                                         
L1         "27nH 350mA 0.46ohm 0402" TopLayer FP-LQG15HH_02-IPC_C          169.291       1417.323      180      "Multilayer type RF Inductor 27nH ±5% 0.46O 350mA 0402"                                           
J2         U.FL-R-SMT-1(10)          TopLayer FP-U_FL-R-SMT-1_10-MFG       133.858       1540.846      180      "CONN U.FL RCPT STR 50 OHM SMD"                                                                   
J1         OCPTAP_M2_FINGERS         TopLayer OCPTAP_M2_FINGERS            433.071       55.118        0        ""                                                                                                
C4         "47pF 50V 0402"           TopLayer c0402                        153.543       1350.394      270      "0402 47 pF 50 V ±5 % Tolerance NP0 SMT Multilayer Ceramic Capacitor"                             
C3         "10nF 50V 0402"           TopLayer c0402                        685.039       535.433       180      "CAP CER 10000PF 50V X7R 0402"                                                                    
C2         "100nF 10V 0402"          TopLayer c0402                        685.039       582.677       180      "CL05 Series 0.1 uF 10 V ±10 % Tolerance X7R SMT Multilayer Ceramic Capacitor"                    
C1         "1uF 6V3 0402"            TopLayer c0402                        685.039       629.921       180      "0402 1 uF 6.3 V ±10% Tolerance X7R Multilayer Ceramic Capacitor"                                 
